# T6G (Grand Teton) — schematic netlist excerpt (pin names and nets, part order shuffled) for the footprints in the layout excerpt that follows; sources: Cadence DE-HDL packaged netlist, KiCad conversion of 04192023_DAF0TMB3IC0_F0TG_MB_C_brd_V02_OCP.brd

X27  TP_TDR_4P_FTS  TP_TDR_4P_DIP EMPTY  pkg TH  page 260
  S1  = TDR_DIFF_80_IN5_DN
  P1  = T1_GND
  P2  = T1_GND
  S2  = TDR_DIFF_80_IN5_DP

R4170  Q_RES  33.2 1% CHIP  pkg 0402LF  page 81 : A = GPU_3V3IO_RSVD1_ISO_R ; B = GPU_3V3IO_RSVD1_ISO

(kicad_pcb
	(version 20260206)
	(generator "pcbnew")
	(generator_version "10.0")
	(general
		(thickness 1.6)
		(legacy_teardrops no)
	)
	(paper "A4")
	(title_block
		(title "04192023_DAF0TMB3IC0_F0TG_MB_C_brd_V02_OCP.brd")
		(comment 1 "Grand Teton / footprints 5277-5278 of 8354")
	)
	(layers
		(0 "F.Cu" signal "TOP")
		(4 "In1.Cu" signal "GND")
		(6 "In2.Cu" signal "IN1")
		(8 "In3.Cu" signal "GND1")
		(10 "In4.Cu" signal "IN2")
		(12 "In5.Cu" signal "GND2")
		(14 "In6.Cu" signal "IN3")
		(16 "In7.Cu" signal "GND3")
		(18 "In8.Cu" signal "VCC")
		(20 "In9.Cu" signal "VCC1")
		(22 "In10.Cu" signal "GND4")
		(24 "In11.Cu" signal "IN4")
		(26 "In12.Cu" signal "GND5")
		(28 "In13.Cu" signal "IN5")
		(30 "In14.Cu" signal "GND6")
		(32 "In15.Cu" signal "IN6")
		(34 "In16.Cu" signal "GND7")
		(2 "B.Cu" signal "BOTTOM")
		(9 "F.Adhes" user "F.Adhesive")
		(11 "B.Adhes" user "B.Adhesive")
		(13 "F.Paste" user "Package Geometry/Pastemask Top")
		(15 "B.Paste" user "Package Geometry/Pastemask Bottom")
		(5 "F.SilkS" user "Ref Des/Silkscreen Top")
		(7 "B.SilkS" user "Ref Des/Silkscreen Bottom")
		(1 "F.Mask" user "Board Geometry/Soldermask Top")
		(3 "B.Mask" user "Board Geometry/Soldermask Bottom")
		(17 "Dwgs.User" user "User.Drawings")
		(19 "Cmts.User" user "User.Comments")
		(21 "Eco1.User" user "User.Eco1")
		(23 "Eco2.User" user "User.Eco2")
		(25 "Edge.Cuts" user "Board Geometry/Outline")
		(27 "Margin" user)
		(31 "F.CrtYd" user "Package Geometry/Place Bound Top")
		(29 "B.CrtYd" user "Package Geometry/Place Bound Bottom")
		(35 "F.Fab" user "Ref Des/Assembly Top")
		(33 "B.Fab" user "Ref Des/Assembly Bottom")
	)
	(footprint ""
		(layer "B.Cu")
		(at 197.269608 -117.689376 180)
		(property "Reference" "R4170"
			(at 0 0 0)
			(layer "B.SilkS")
			(hide yes)
			(effects
				(font
					(size 1.27 1.27)
				)
				(justify mirror)
			)
		)
		(property "Value" ""
			(at 0 0 0)
			(layer "B.Fab")
			(effects
				(font
					(size 1.27 1.27)
				)
				(justify mirror)
			)
		)
		(duplicate_pad_numbers_are_jumpers no)
		(fp_line
			(start 0.7874 0.4064)
			(end 0.7874 -0.4064)
			(stroke
				(width 0.1524)
				(type default)
			)
			(layer "B.SilkS")
		)
		(fp_line
			(start 0.7874 -0.4064)
			(end -0.7874 -0.4064)
			(stroke
				(width 0.1524)
				(type default)
			)
			(layer "B.SilkS")
		)
		(fp_line
			(start -0.7874 0.4064)
			(end 0.7874 0.4064)
			(stroke
				(width 0.1524)
				(type default)
			)
			(layer "B.SilkS")
		)
		(fp_line
			(start -0.7874 -0.4064)
			(end -0.7874 0.4064)
			(stroke
				(width 0.1524)
				(type default)
			)
			(layer "B.SilkS")
		)
		(fp_line
			(start 0.67945 0.3048)
			(end 0.67945 -0.305054)
			(stroke
				(width 0.1)
				(type default)
			)
			(layer "B.Fab")
		)
		(fp_line
			(start 0.67945 -0.305054)
			(end 0.12065 -0.305054)
			(stroke
				(width 0.1)
				(type default)
			)
			(layer "B.Fab")
		)
		(fp_line
			(start 0.12065 0.3048)
			(end 0.67945 0.3048)
			(stroke
				(width 0.1)
				(type default)
			)
			(layer "B.Fab")
		)
		(fp_line
			(start 0.12065 0.2794)
			(end 0.12065 0.3048)
			(stroke
				(width 0.1)
				(type default)
			)
			(layer "B.Fab")
		)
		(fp_line
			(start 0.12065 -0.2794)
			(end -0.12065 -0.2794)
			(stroke
				(width 0.1)
				(type default)
			)
			(layer "B.Fab")
		)
		(fp_line
			(start 0.12065 -0.305054)
			(end 0.12065 -0.2794)
			(stroke
				(width 0.1)
				(type default)
			)
			(layer "B.Fab")
		)
		(fp_line
			(start -0.120396 0.3048)
			(end -0.120396 0.2794)
			(stroke
				(width 0.1)
				(type default)
			)
			(layer "B.Fab")
		)
		(fp_line
			(start -0.120396 0.2794)
			(end 0.12065 0.2794)
			(stroke
				(width 0.1)
				(type default)
			)
			(layer "B.Fab")
		)
		(fp_line
			(start -0.12065 -0.2794)
			(end -0.12065 -0.3048)
			(stroke
				(width 0.1)
				(type default)
			)
			(layer "B.Fab")
		)
		(fp_line
			(start -0.12065 -0.3048)
			(end -0.67945 -0.3048)
			(stroke
				(width 0.1)
				(type default)
			)
			(layer "B.Fab")
		)
		(fp_line
			(start -0.67945 0.3048)
			(end -0.120396 0.3048)
			(stroke
				(width 0.1)
				(type default)
			)
			(layer "B.Fab")
		)
		(fp_line
			(start -0.67945 -0.3048)
			(end -0.67945 0.3048)
			(stroke
				(width 0.1)
				(type default)
			)
			(layer "B.Fab")
		)
		(pad "1" smd circle
			(at 0.40005 0)
			(size 0 0)
			(layers "B.Cu" "B.Mask" "B.Paste")
			(net "GPU_3V3IO_RSVD1_ISO_R")
		)
		(pad "2" smd circle
			(at -0.40005 0)
			(size 0 0)
			(layers "B.Cu" "B.Mask" "B.Paste")
			(net "GPU_3V3IO_RSVD1_ISO")
		)
	)
	(footprint ""
		(layer "B.Cu")
		(at 511.924808 -298.345606 -90)
		(property "Reference" "X27"
			(at 3.097276 3.214878 270)
			(unlocked yes)
			(layer "B.SilkS")
			(effects
				(font
					(size 0.7874 0.5842)
					(thickness 0.1524)
				)
				(justify left mirror)
			)
		)
		(property "Value" ""
			(at 0 0 90)
			(layer "B.Fab")
			(effects
				(font
					(size 1.27 1.27)
				)
				(justify mirror)
			)
		)
		(property "User Part Number" "N_A"
			(at -1.30175 1.27 180)
			(unlocked yes)
			(layer "Cmts.User")
			(hide yes)
			(effects
				(font
					(size 0.635 0.4064)
					(thickness 0.1524)
				)
				(justify mirror)
			)
		)
		(property "Device Type" "TP_TDR_4P_FTS_TH-TP_TDR_4P_DIP,EMPTY,TP15"
			(at -1.30175 1.27 180)
			(unlocked yes)
			(layer "B.Fab")
			(hide yes)
			(effects
				(font
					(size 0.635 0.4064)
					(thickness 0.1524)
				)
				(justify mirror)
			)
		)
		(duplicate_pad_numbers_are_jumpers no)
		(fp_line
			(start -2.54 3.81)
			(end -2.54 3.6703)
			(stroke
				(width 0.1524)
				(type default)
			)
			(layer "B.SilkS")
		)
		(fp_line
			(start 0 3.81)
			(end -2.54 3.81)
			(stroke
				(width 0.1524)
				(type default)
			)
			(layer "B.SilkS")
		)
		(fp_line
			(start 0 3.175)
			(end 0 3.81)
			(stroke
				(width 0.1524)
				(type default)
			)
			(layer "B.SilkS")
		)
		(fp_line
			(start -2.54 1.4097)
			(end -2.54 1.1303)
			(stroke
				(width 0.1524)
				(type default)
			)
			(layer "B.SilkS")
		)
		(fp_line
			(start 0 0.635)
			(end 0 1.905)
			(stroke
				(width 0.1524)
				(type default)
			)
			(layer "B.SilkS")
		)
		(fp_line
			(start -2.54 -1.1303)
			(end -2.54 -1.27)
			(stroke
				(width 0.1524)
				(type default)
			)
			(layer "B.SilkS")
		)
		(fp_line
			(start -2.54 -1.27)
			(end 0 -1.27)
			(stroke
				(width 0.1524)
				(type default)
			)
			(layer "B.SilkS")
		)
		(fp_line
			(start 0 -1.27)
			(end 0 -0.635)
			(stroke
				(width 0.1524)
				(type default)
			)
			(layer "B.SilkS")
		)
		(fp_poly
			(pts
				(xy 2.285746 -0.762) (xy 2.285746 0.762) (xy 0.761746 0)
			)
			(stroke
				(width 0)
				(type default)
			)
			(fill yes)
			(layer "B.SilkS")
		)
		(fp_line
			(start -2.54 3.81)
			(end -2.54 -1.27)
			(stroke
				(width 0.1)
				(type default)
			)
			(layer "B.Fab")
		)
		(fp_line
			(start 0 3.81)
			(end -2.54 3.81)
			(stroke
				(width 0.1)
				(type default)
			)
			(layer "B.Fab")
		)
		(fp_line
			(start -2.54 -1.27)
			(end 0 -1.27)
			(stroke
				(width 0.1)
				(type default)
			)
			(layer "B.Fab")
		)
		(fp_line
			(start 0 -1.27)
			(end 0 3.81)
			(stroke
				(width 0.1)
				(type default)
			)
			(layer "B.Fab")
		)
		(fp_poly
			(pts
				(xy 0.761746 0) (xy 2.285746 -0.762) (xy 2.285746 0.762)
			)
			(stroke
				(width 0)
				(type default)
			)
			(fill yes)
			(layer "B.Fab")
		)
		(pad "1" thru_hole circle
			(at 0 0 90)
			(size 1.0033 1.0033)
			(drill 0.249936)
			(layers "*.Cu" "*.Mask")
			(remove_unused_layers no)
			(net "TDR_DIFF_80_IN5_DN")
			(clearance 0.10795)
			(padstack
				(mode front_inner_back)
				(layer "Inner"
					(shape circle)
					(size 0.8001 0.8001)
					(clearance 0.1524)
				)
				(layer "B.Cu"
					(shape circle)
					(size 1.0033 1.0033)
					(thermal_gap 0.10795)
					(clearance 0.10795)
				)
			)
		)
		(pad "2" thru_hole circle
			(at -2.54 0 90)
			(size 1.9939 1.9939)
			(drill 0.249936)
			(layers "*.Cu" "*.Mask")
			(remove_unused_layers no)
			(net "T1_GND")
			(clearance 0.10795)
			(padstack
				(mode front_inner_back)
				(layer "Inner"
					(shape circle)
					(size 0.8001 0.8001)
					(clearance 0.1524)
				)
				(layer "B.Cu"
					(shape circle)
					(size 1.9939 1.9939)
					(thermal_gap 0.10795)
					(clearance 0.10795)
				)
			)
		)
		(pad "3" thru_hole circle
			(at -2.54 2.54 90)
			(size 1.9939 1.9939)
			(drill 0.249936)
			(layers "*.Cu" "*.Mask")
			(remove_unused_layers no)
			(net "T1_GND")
			(clearance 0.10795)
			(padstack
				(mode front_inner_back)
				(layer "Inner"
					(shape circle)
					(size 0.8001 0.8001)
					(clearance 0.1524)
				)
				(layer "B.Cu"
					(shape circle)
					(size 1.9939 1.9939)
					(thermal_gap 0.10795)
					(clearance 0.10795)
				)
			)
		)
		(pad "4" thru_hole circle
			(at 0 2.54 90)
			(size 1.0033 1.0033)
			(drill 0.249936)
			(layers "*.Cu" "*.Mask")
			(remove_unused_layers no)
			(net "TDR_DIFF_80_IN5_DP")
			(clearance 0.10795)
			(padstack
				(mode front_inner_back)
				(layer "Inner"
					(shape circle)
					(size 0.8001 0.8001)
					(clearance 0.1524)
				)
				(layer "B.Cu"
					(shape circle)
					(size 1.0033 1.0033)
					(thermal_gap 0.10795)
					(clearance 0.10795)
				)
			)
		)
	)
)
